# T6G (Grand Teton) — schematic netlist excerpt (pin names and nets, part order shuffled) for the footprints in the layout excerpt that follows; sources: Cadence DE-HDL packaged netlist, KiCad conversion of 04192023_DAF0TMB3IC0_F0TG_MB_C_brd_V02_OCP.brd

R2828  Q_RES  100K 1% CHIP  pkg 0402LF  page 127 : A = P3V3_AUX ; B = RST_BMC_FROM_SWB_N
PC473  Q_CAPP  100UF 16V 20% OSCON  pkg SMLF  page 365 : A = SW_P12V_AUX_P0V9_RETIMER_CPU1_FLT ; B = GND
R1126  Q_RES  0 5% CHIP  pkg 0201LF  page 310 : A = NCF_A1_CPU0_P3_GND ; B = GND
R678  Q_RES  33.2 1% CHIP  pkg 0201LF  page 289 : A = SMB_RT_CPU0_P1_ROM_R_SCL ; B = SMB_RT_CPU0_P1_ROM_SCL

(kicad_pcb
	(version 20260206)
	(generator "pcbnew")
	(generator_version "10.0")
	(general
		(thickness 1.6)
		(legacy_teardrops no)
	)
	(paper "A4")
	(title_block
		(title "04192023_DAF0TMB3IC0_F0TG_MB_C_brd_V02_OCP.brd")
		(comment 1 "Grand Teton / footprints 1233-1236 of 8354")
	)
	(layers
		(0 "F.Cu" signal "TOP")
		(4 "In1.Cu" signal "GND")
		(6 "In2.Cu" signal "IN1")
		(8 "In3.Cu" signal "GND1")
		(10 "In4.Cu" signal "IN2")
		(12 "In5.Cu" signal "GND2")
		(14 "In6.Cu" signal "IN3")
		(16 "In7.Cu" signal "GND3")
		(18 "In8.Cu" signal "VCC")
		(20 "In9.Cu" signal "VCC1")
		(22 "In10.Cu" signal "GND4")
		(24 "In11.Cu" signal "IN4")
		(26 "In12.Cu" signal "GND5")
		(28 "In13.Cu" signal "IN5")
		(30 "In14.Cu" signal "GND6")
		(32 "In15.Cu" signal "IN6")
		(34 "In16.Cu" signal "GND7")
		(2 "B.Cu" signal "BOTTOM")
		(9 "F.Adhes" user "F.Adhesive")
		(11 "B.Adhes" user "B.Adhesive")
		(13 "F.Paste" user "Package Geometry/Pastemask Top")
		(15 "B.Paste" user "Package Geometry/Pastemask Bottom")
		(5 "F.SilkS" user "Ref Des/Silkscreen Top")
		(7 "B.SilkS" user "Ref Des/Silkscreen Bottom")
		(1 "F.Mask" user "Board Geometry/Soldermask Top")
		(3 "B.Mask" user "Board Geometry/Soldermask Bottom")
		(17 "Dwgs.User" user "User.Drawings")
		(19 "Cmts.User" user "User.Comments")
		(21 "Eco1.User" user "User.Eco1")
		(23 "Eco2.User" user "User.Eco2")
		(25 "Edge.Cuts" user "Board Geometry/Outline")
		(27 "Margin" user)
		(31 "F.CrtYd" user "Package Geometry/Place Bound Top")
		(29 "B.CrtYd" user "Package Geometry/Place Bound Bottom")
		(35 "F.Fab" user "Ref Des/Assembly Top")
		(33 "B.Fab" user "Ref Des/Assembly Bottom")
	)
	(footprint ""
		(layer "F.Cu")
		(at 31.726378 -401.398232)
		(property "Reference" "PC473"
			(at -1.627378 -3.578098 0)
			(unlocked yes)
			(layer "F.SilkS")
			(effects
				(font
					(size 0.7874 0.5842)
					(thickness 0.1524)
				)
				(justify left)
			)
		)
		(property "Value" ""
			(at 0 0 0)
			(layer "F.Fab")
			(effects
				(font
					(size 1.27 1.27)
				)
			)
		)
		(duplicate_pad_numbers_are_jumpers no)
		(fp_line
			(start -2.750058 -1.988058)
			(end -2.750058 -0.9398)
			(stroke
				(width 0.1524)
				(type default)
			)
			(layer "F.SilkS")
		)
		(fp_line
			(start -2.750058 0.9398)
			(end -2.750058 1.988058)
			(stroke
				(width 0.1524)
				(type default)
			)
			(layer "F.SilkS")
		)
		(fp_line
			(start -2.750058 1.988058)
			(end -1.988058 2.750058)
			(stroke
				(width 0.1524)
				(type default)
			)
			(layer "F.SilkS")
		)
		(fp_line
			(start -1.988058 -2.750058)
			(end -2.750058 -1.988058)
			(stroke
				(width 0.1524)
				(type default)
			)
			(layer "F.SilkS")
		)
		(fp_line
			(start -1.988058 2.750058)
			(end 2.750058 2.750058)
			(stroke
				(width 0.1524)
				(type default)
			)
			(layer "F.SilkS")
		)
		(fp_line
			(start 2.750058 -2.750058)
			(end -1.988058 -2.750058)
			(stroke
				(width 0.1524)
				(type default)
			)
			(layer "F.SilkS")
		)
		(fp_line
			(start 2.750058 -0.9398)
			(end 2.750058 -2.750058)
			(stroke
				(width 0.1524)
				(type default)
			)
			(layer "F.SilkS")
		)
		(fp_line
			(start 2.750058 2.750058)
			(end 2.750058 0.9398)
			(stroke
				(width 0.1524)
				(type default)
			)
			(layer "F.SilkS")
		)
		(fp_line
			(start -2.750058 -2.750058)
			(end -2.750058 2.750058)
			(stroke
				(width 0.1)
				(type default)
			)
			(layer "F.Fab")
		)
		(fp_line
			(start -2.750058 2.750058)
			(end 2.750058 2.750058)
			(stroke
				(width 0.1)
				(type default)
			)
			(layer "F.Fab")
		)
		(fp_line
			(start 2.750058 -2.750058)
			(end -2.750058 -2.750058)
			(stroke
				(width 0.1)
				(type default)
			)
			(layer "F.Fab")
		)
		(fp_line
			(start 2.750058 2.750058)
			(end 2.750058 -2.750058)
			(stroke
				(width 0.1)
				(type default)
			)
			(layer "F.Fab")
		)
		(pad "1" smd rect
			(at -2.199894 0 90)
			(size 1.6002 3.0226)
			(layers "F.Cu" "F.Mask" "F.Paste")
			(net "SW_P12V_AUX_P0V9_RETIMER_CPU1_FLT")
		)
		(pad "2" smd rect
			(at 2.199894 0 90)
			(size 1.6002 3.0226)
			(layers "F.Cu" "F.Mask" "F.Paste")
			(net "GND")
		)
	)
	(footprint ""
		(layer "F.Cu")
		(at 420.246302 -440.012836 -90)
		(property "Reference" "R2828"
			(at 0 0 270)
			(layer "F.SilkS")
			(hide yes)
			(effects
				(font
					(size 1.27 1.27)
				)
			)
		)
		(property "Value" ""
			(at 0 0 270)
			(layer "F.Fab")
			(effects
				(font
					(size 1.27 1.27)
				)
			)
		)
		(duplicate_pad_numbers_are_jumpers no)
		(fp_line
			(start -0.7874 0.4064)
			(end -0.7874 -0.4064)
			(stroke
				(width 0.1524)
				(type default)
			)
			(layer "F.SilkS")
		)
		(fp_line
			(start 0.7874 0.4064)
			(end -0.7874 0.4064)
			(stroke
				(width 0.1524)
				(type default)
			)
			(layer "F.SilkS")
		)
		(fp_line
			(start -0.7874 -0.4064)
			(end 0.7874 -0.4064)
			(stroke
				(width 0.1524)
				(type default)
			)
			(layer "F.SilkS")
		)
		(fp_line
			(start 0.7874 -0.4064)
			(end 0.7874 0.4064)
			(stroke
				(width 0.1524)
				(type default)
			)
			(layer "F.SilkS")
		)
		(fp_line
			(start -0.67945 0.3048)
			(end -0.67945 -0.305054)
			(stroke
				(width 0.1)
				(type default)
			)
			(layer "F.Fab")
		)
		(fp_line
			(start -0.12065 0.3048)
			(end -0.67945 0.3048)
			(stroke
				(width 0.1)
				(type default)
			)
			(layer "F.Fab")
		)
		(fp_line
			(start 0.120396 0.3048)
			(end 0.120396 0.2794)
			(stroke
				(width 0.1)
				(type default)
			)
			(layer "F.Fab")
		)
		(fp_line
			(start 0.67945 0.3048)
			(end 0.120396 0.3048)
			(stroke
				(width 0.1)
				(type default)
			)
			(layer "F.Fab")
		)
		(fp_line
			(start -0.12065 0.2794)
			(end -0.12065 0.3048)
			(stroke
				(width 0.1)
				(type default)
			)
			(layer "F.Fab")
		)
		(fp_line
			(start 0.120396 0.2794)
			(end -0.12065 0.2794)
			(stroke
				(width 0.1)
				(type default)
			)
			(layer "F.Fab")
		)
		(fp_line
			(start -0.12065 -0.2794)
			(end 0.12065 -0.2794)
			(stroke
				(width 0.1)
				(type default)
			)
			(layer "F.Fab")
		)
		(fp_line
			(start 0.12065 -0.2794)
			(end 0.12065 -0.3048)
			(stroke
				(width 0.1)
				(type default)
			)
			(layer "F.Fab")
		)
		(fp_line
			(start 0.12065 -0.3048)
			(end 0.67945 -0.3048)
			(stroke
				(width 0.1)
				(type default)
			)
			(layer "F.Fab")
		)
		(fp_line
			(start 0.67945 -0.3048)
			(end 0.67945 0.3048)
			(stroke
				(width 0.1)
				(type default)
			)
			(layer "F.Fab")
		)
		(fp_line
			(start -0.67945 -0.305054)
			(end -0.12065 -0.305054)
			(stroke
				(width 0.1)
				(type default)
			)
			(layer "F.Fab")
		)
		(fp_line
			(start -0.12065 -0.305054)
			(end -0.12065 -0.2794)
			(stroke
				(width 0.1)
				(type default)
			)
			(layer "F.Fab")
		)
		(pad "1" smd circle
			(at -0.40005 0 270)
			(size 0 0)
			(layers "F.Cu" "F.Mask" "F.Paste")
			(net "P3V3_AUX")
		)
		(pad "2" smd circle
			(at 0.40005 0 270)
			(size 0 0)
			(layers "F.Cu" "F.Mask" "F.Paste")
			(net "RST_BMC_FROM_SWB_N")
		)
	)
	(footprint ""
		(layer "F.Cu")
		(at 392.081258 -402.9202 -90)
		(property "Reference" "R1126"
			(at 0 0 270)
			(layer "F.SilkS")
			(hide yes)
			(effects
				(font
					(size 1.27 1.27)
				)
			)
		)
		(property "Value" ""
			(at 0 0 270)
			(layer "F.Fab")
			(effects
				(font
					(size 1.27 1.27)
				)
			)
		)
		(duplicate_pad_numbers_are_jumpers no)
		(fp_line
			(start -0.32512 0.175006)
			(end -0.32512 -0.175006)
			(stroke
				(width 0.1)
				(type default)
			)
			(layer "F.Fab")
		)
		(fp_line
			(start 0.32512 0.175006)
			(end -0.32512 0.175006)
			(stroke
				(width 0.1)
				(type default)
			)
			(layer "F.Fab")
		)
		(fp_line
			(start -0.32512 -0.175006)
			(end 0.32512 -0.175006)
			(stroke
				(width 0.1)
				(type default)
			)
			(layer "F.Fab")
		)
		(fp_line
			(start 0.32512 -0.175006)
			(end 0.32512 0.175006)
			(stroke
				(width 0.1)
				(type default)
			)
			(layer "F.Fab")
		)
		(pad "1" smd rect
			(at -0.2667 0 270)
			(size 0.3048 0.381)
			(layers "F.Cu" "F.Mask" "F.Paste")
			(net "NCF_A1_CPU0_P3_GND")
		)
		(pad "2" smd rect
			(at 0.2667 0 90)
			(size 0.3048 0.381)
			(layers "F.Cu" "F.Mask" "F.Paste")
			(net "GND")
		)
	)
	(footprint ""
		(layer "F.Cu")
		(at 290.311586 -398.613376 90)
		(property "Reference" "R678"
			(at 0 0 90)
			(layer "F.SilkS")
			(hide yes)
			(effects
				(font
					(size 1.27 1.27)
				)
			)
		)
		(property "Value" ""
			(at 0 0 90)
			(layer "F.Fab")
			(effects
				(font
					(size 1.27 1.27)
				)
			)
		)
		(duplicate_pad_numbers_are_jumpers no)
		(fp_line
			(start 0.32512 -0.175006)
			(end 0.32512 0.175006)
			(stroke
				(width 0.1)
				(type default)
			)
			(layer "F.Fab")
		)
		(fp_line
			(start -0.32512 -0.175006)
			(end 0.32512 -0.175006)
			(stroke
				(width 0.1)
				(type default)
			)
			(layer "F.Fab")
		)
		(fp_line
			(start 0.32512 0.175006)
			(end -0.32512 0.175006)
			(stroke
				(width 0.1)
				(type default)
			)
			(layer "F.Fab")
		)
		(fp_line
			(start -0.32512 0.175006)
			(end -0.32512 -0.175006)
			(stroke
				(width 0.1)
				(type default)
			)
			(layer "F.Fab")
		)
		(pad "1" smd rect
			(at -0.2667 0 90)
			(size 0.3048 0.381)
			(layers "F.Cu" "F.Mask" "F.Paste")
			(net "SMB_RT_CPU0_P1_ROM_R_SCL")
		)
		(pad "2" smd rect
			(at 0.2667 0 270)
			(size 0.3048 0.381)
			(layers "F.Cu" "F.Mask" "F.Paste")
			(net "SMB_RT_CPU0_P1_ROM_SCL")
		)
	)
)
